(kicad_pcb
	(version 20260206)
	(generator "pcbnew")
	(generator_version "10.0")
	(general
		(thickness 1.6)
		(legacy_teardrops no)
	)
	(paper "A4")
	(title_block
		(title "03242023_DA0F0TMBIJ0_F0T_Motherboard_J_brd_V01_OCP.brd")
		(comment 1 "Grand Teton / footprint 3456 of 6105 (J35), pads 110-175 of 175")
	)
	(layers
		(0 "F.Cu" signal "TOP")
		(4 "In1.Cu" signal "GND")
		(6 "In2.Cu" signal "IN1")
		(8 "In3.Cu" signal "GND1")
		(10 "In4.Cu" signal "IN2")
		(12 "In5.Cu" signal "GND2")
		(14 "In6.Cu" signal "IN3")
		(16 "In7.Cu" signal "GND3")
		(18 "In8.Cu" signal "VCC")
		(20 "In9.Cu" signal "VCC1")
		(22 "In10.Cu" signal "GND4")
		(24 "In11.Cu" signal "IN4")
		(26 "In12.Cu" signal "GND5")
		(28 "In13.Cu" signal "IN5")
		(30 "In14.Cu" signal "GND6")
		(32 "In15.Cu" signal "IN6")
		(34 "In16.Cu" signal "GND7")
		(2 "B.Cu" signal "BOTTOM")
		(9 "F.Adhes" user "F.Adhesive")
		(11 "B.Adhes" user "B.Adhesive")
		(13 "F.Paste" user "Package Geometry/Pastemask Top")
		(15 "B.Paste" user "Package Geometry/Pastemask Bottom")
		(5 "F.SilkS" user "Ref Des/Silkscreen Top")
		(7 "B.SilkS" user "Ref Des/Silkscreen Bottom")
		(1 "F.Mask" user "Board Geometry/Soldermask Top")
		(3 "B.Mask" user "Board Geometry/Soldermask Bottom")
		(17 "Dwgs.User" user "User.Drawings")
		(19 "Cmts.User" user "User.Comments")
		(21 "Eco1.User" user "User.Eco1")
		(23 "Eco2.User" user "User.Eco2")
		(25 "Edge.Cuts" user "Board Geometry/Outline")
		(27 "Margin" user)
		(31 "F.CrtYd" user "Package Geometry/Place Bound Top")
		(29 "B.CrtYd" user "Package Geometry/Place Bound Bottom")
		(35 "F.Fab" user "Ref Des/Assembly Top")
		(33 "B.Fab" user "Ref Des/Assembly Bottom")
	)
	(footprint ""
		(layer "F.Cu")
		(at 47.401988 -5.569966 -90)
		(property "Reference" "J35"
			(at -16.848074 29.242004 0)
			(unlocked yes)
			(layer "F.SilkS")
			(effects
				(font
					(size 0.7874 0.5842)
					(thickness 0.1524)
				)
				(justify left)
			)
		)
		(property "Value" ""
			(at 0 0 270)
			(layer "F.Fab")
			(effects
				(font
					(size 1.27 1.27)
				)
			)
		)
		(duplicate_pad_numbers_are_jumpers no)
		(pad "B38" smd rect
			(at -5.700014 7.14502 180)
			(size 0.381 1.4478)
			(layers "F.Cu" "F.Mask" "F.Paste")
			(net "GND")
		)
		(pad "B39" smd rect
			(at -5.700014 7.744968 180)
			(size 0.381 1.4478)
			(layers "F.Cu" "F.Mask" "F.Paste")
			(net "P5E_CPU1_PE1_TX_C_DN<7>")
		)
		(pad "B40" smd rect
			(at -5.700014 8.344916 180)
			(size 0.381 1.4478)
			(layers "F.Cu" "F.Mask" "F.Paste")
			(net "P5E_CPU1_PE1_TX_C_DP<7>")
		)
		(pad "B41" smd rect
			(at -5.700014 8.945118 180)
			(size 0.381 1.4478)
			(layers "F.Cu" "F.Mask" "F.Paste")
			(net "GND")
		)
		(pad "B42" smd rect
			(at -5.700014 9.545066 180)
			(size 0.381 1.4478)
			(layers "F.Cu" "F.Mask" "F.Paste")
			(net "OCP_V3_2_PRSNT0_R_N")
		)
		(pad "B43" smd rect
			(at -5.700014 14.454886 180)
			(size 0.381 1.4478)
			(layers "F.Cu" "F.Mask" "F.Paste")
			(net "GND")
		)
		(pad "B44" smd rect
			(at -5.700014 15.055088 180)
			(size 0.381 1.4478)
			(layers "F.Cu" "F.Mask" "F.Paste")
			(net "P5E_CPU1_PE1_TX_C_DP<8>")
		)
		(pad "B45" smd rect
			(at -5.700014 15.655036 180)
			(size 0.381 1.4478)
			(layers "F.Cu" "F.Mask" "F.Paste")
			(net "P5E_CPU1_PE1_TX_C_DN<8>")
		)
		(pad "B46" smd rect
			(at -5.700014 16.254984 180)
			(size 0.381 1.4478)
			(layers "F.Cu" "F.Mask" "F.Paste")
			(net "GND")
		)
		(pad "B47" smd rect
			(at -5.700014 16.854932 180)
			(size 0.381 1.4478)
			(layers "F.Cu" "F.Mask" "F.Paste")
			(net "P5E_CPU1_PE1_TX_C_DN<9>")
		)
		(pad "B48" smd rect
			(at -5.700014 17.45488 180)
			(size 0.381 1.4478)
			(layers "F.Cu" "F.Mask" "F.Paste")
			(net "P5E_CPU1_PE1_TX_C_DP<9>")
		)
		(pad "B49" smd rect
			(at -5.700014 18.055082 180)
			(size 0.381 1.4478)
			(layers "F.Cu" "F.Mask" "F.Paste")
			(net "GND")
		)
		(pad "B50" smd rect
			(at -5.700014 18.65503 180)
			(size 0.381 1.4478)
			(layers "F.Cu" "F.Mask" "F.Paste")
			(net "P5E_CPU1_PE1_TX_C_DP<10>")
		)
		(pad "B51" smd rect
			(at -5.700014 19.254978 180)
			(size 0.381 1.4478)
			(layers "F.Cu" "F.Mask" "F.Paste")
			(net "P5E_CPU1_PE1_TX_C_DN<10>")
		)
		(pad "B52" smd rect
			(at -5.700014 19.854926 180)
			(size 0.381 1.4478)
			(layers "F.Cu" "F.Mask" "F.Paste")
			(net "GND")
		)
		(pad "B53" smd rect
			(at -5.700014 20.455128 180)
			(size 0.381 1.4478)
			(layers "F.Cu" "F.Mask" "F.Paste")
			(net "P5E_CPU1_PE1_TX_C_DN<11>")
		)
		(pad "B54" smd rect
			(at -5.700014 21.055076 180)
			(size 0.381 1.4478)
			(layers "F.Cu" "F.Mask" "F.Paste")
			(net "P5E_CPU1_PE1_TX_C_DP<11>")
		)
		(pad "B55" smd rect
			(at -5.700014 21.655024 180)
			(size 0.381 1.4478)
			(layers "F.Cu" "F.Mask" "F.Paste")
			(net "GND")
		)
		(pad "B56" smd rect
			(at -5.700014 22.254972 180)
			(size 0.381 1.4478)
			(layers "F.Cu" "F.Mask" "F.Paste")
			(net "P5E_CPU1_PE1_TX_C_DP<12>")
		)
		(pad "B57" smd rect
			(at -5.700014 22.85492 180)
			(size 0.381 1.4478)
			(layers "F.Cu" "F.Mask" "F.Paste")
			(net "P5E_CPU1_PE1_TX_C_DN<12>")
		)
		(pad "B58" smd rect
			(at -5.700014 23.455122 180)
			(size 0.381 1.4478)
			(layers "F.Cu" "F.Mask" "F.Paste")
			(net "GND")
		)
		(pad "B59" smd rect
			(at -5.700014 24.05507 180)
			(size 0.381 1.4478)
			(layers "F.Cu" "F.Mask" "F.Paste")
			(net "P5E_CPU1_PE1_TX_C_DN<13>")
		)
		(pad "B60" smd rect
			(at -5.700014 24.655018 180)
			(size 0.381 1.4478)
			(layers "F.Cu" "F.Mask" "F.Paste")
			(net "P5E_CPU1_PE1_TX_C_DP<13>")
		)
		(pad "B61" smd rect
			(at -5.700014 25.254966 180)
			(size 0.381 1.4478)
			(layers "F.Cu" "F.Mask" "F.Paste")
			(net "GND")
		)
		(pad "B62" smd rect
			(at -5.700014 25.854914 180)
			(size 0.381 1.4478)
			(layers "F.Cu" "F.Mask" "F.Paste")
			(net "P5E_CPU1_PE1_TX_C_DP<14>")
		)
		(pad "B63" smd rect
			(at -5.700014 26.455116 180)
			(size 0.381 1.4478)
			(layers "F.Cu" "F.Mask" "F.Paste")
			(net "P5E_CPU1_PE1_TX_C_DN<14>")
		)
		(pad "B64" smd rect
			(at -5.700014 27.055064 180)
			(size 0.381 1.4478)
			(layers "F.Cu" "F.Mask" "F.Paste")
			(net "GND")
		)
		(pad "B65" smd rect
			(at -5.700014 27.655012 180)
			(size 0.381 1.4478)
			(layers "F.Cu" "F.Mask" "F.Paste")
			(net "P5E_CPU1_PE1_TX_C_DN<15>")
		)
		(pad "B66" smd rect
			(at -5.700014 28.25496 180)
			(size 0.381 1.4478)
			(layers "F.Cu" "F.Mask" "F.Paste")
			(net "P5E_CPU1_PE1_TX_C_DP<15>")
		)
		(pad "B67" smd rect
			(at -5.700014 28.854908 180)
			(size 0.381 1.4478)
			(layers "F.Cu" "F.Mask" "F.Paste")
			(net "GND")
		)
		(pad "B68" smd rect
			(at -5.700014 29.45511 180)
			(size 0.381 1.4478)
			(layers "F.Cu" "F.Mask" "F.Paste")
			(net "TP_OCP_V3_2_B68")
		)
		(pad "B69" smd rect
			(at -5.700014 30.055058 180)
			(size 0.381 1.4478)
			(layers "F.Cu" "F.Mask" "F.Paste")
			(net "TP_OCP_V3_2_B69")
		)
		(pad "B70" smd rect
			(at -5.700014 30.655006 180)
			(size 0.381 1.4478)
			(layers "F.Cu" "F.Mask" "F.Paste")
			(net "OCP_V3_2_PRSNT3_R_N")
		)
		(pad "G1" thru_hole circle
			(at 2.400046 -32.759904 180)
			(size 1.6256 1.6256)
			(drill 1.1176)
			(layers "*.Cu" "*.Mask")
			(remove_unused_layers no)
			(net "GND")
			(clearance 0)
		)
		(pad "G2" thru_hole circle
			(at 2.400046 -20.379944 180)
			(size 1.6256 1.6256)
			(drill 1.1176)
			(layers "*.Cu" "*.Mask")
			(remove_unused_layers no)
			(net "GND")
			(clearance 0)
		)
		(pad "G3" thru_hole circle
			(at 2.400046 0 180)
			(size 1.6256 1.6256)
			(drill 1.1176)
			(layers "*.Cu" "*.Mask")
			(remove_unused_layers no)
			(net "GND")
			(clearance 0)
		)
		(pad "G4" thru_hole circle
			(at 2.400046 12.5349 180)
			(size 1.6256 1.6256)
			(drill 1.1176)
			(layers "*.Cu" "*.Mask")
			(remove_unused_layers no)
			(net "GND")
			(clearance 0)
		)
		(pad "G5" thru_hole circle
			(at 2.400046 32.759904 180)
			(size 1.6256 1.6256)
			(drill 1.1176)
			(layers "*.Cu" "*.Mask")
			(remove_unused_layers no)
			(net "GND")
			(clearance 0)
		)
		(pad "OA1" smd rect
			(at -2.750058 -30.660086 180)
			(size 0.381 1.4478)
			(layers "F.Cu" "F.Mask" "F.Paste")
			(net "RST_PERST2_OCP_V3_2_N")
		)
		(pad "OA2" smd rect
			(at -2.750058 -30.059884 180)
			(size 0.381 1.4478)
			(layers "F.Cu" "F.Mask" "F.Paste")
			(net "RST_PERST3_OCP_V3_2_N")
		)
		(pad "OA3" smd rect
			(at -2.750058 -29.459936 180)
			(size 0.381 1.4478)
			(layers "F.Cu" "F.Mask" "F.Paste")
			(net "IRQ_LVC3_OCP_V3_2_WAKE_N")
		)
		(pad "OA4" smd rect
			(at -2.750058 -28.859988 180)
			(size 0.381 1.4478)
			(layers "F.Cu" "F.Mask" "F.Paste")
			(net "OCP_V3_2_ISO1_RBT_ARB_IN")
		)
		(pad "OA5" smd rect
			(at -2.750058 -28.26004 180)
			(size 0.381 1.4478)
			(layers "F.Cu" "F.Mask" "F.Paste")
			(net "OCP_V3_2_ISO2_RBT_ARB_OUT")
		)
		(pad "OA6" smd rect
			(at -2.750058 -27.660092 180)
			(size 0.381 1.4478)
			(layers "F.Cu" "F.Mask" "F.Paste")
			(net "OCP_V3_2_ID1")
		)
		(pad "OA7" smd rect
			(at -2.750058 -27.05989 180)
			(size 0.381 1.4478)
			(layers "F.Cu" "F.Mask" "F.Paste")
			(net "NCSI_OCP_V3_2_TX_EN")
		)
		(pad "OA8" smd rect
			(at -2.750058 -26.459942 180)
			(size 0.381 1.4478)
			(layers "F.Cu" "F.Mask" "F.Paste")
			(net "NCSI_OCP_V3_2_TXD1")
		)
		(pad "OA9" smd rect
			(at -2.750058 -25.859994 180)
			(size 0.381 1.4478)
			(layers "F.Cu" "F.Mask" "F.Paste")
			(net "NCSI_OCP_V3_2_TXD0")
		)
		(pad "OA10" smd rect
			(at -2.750058 -25.260046 180)
			(size 0.381 1.4478)
			(layers "F.Cu" "F.Mask" "F.Paste")
			(net "GND")
		)
		(pad "OA11" smd rect
			(at -2.750058 -24.660098 180)
			(size 0.381 1.4478)
			(layers "F.Cu" "F.Mask" "F.Paste")
			(net "CLK_100M_OCP_V3_2_D_DN")
		)
		(pad "OA12" smd rect
			(at -2.750058 -24.059896 180)
			(size 0.381 1.4478)
			(layers "F.Cu" "F.Mask" "F.Paste")
			(net "CLK_100M_OCP_V3_2_D_DP")
		)
		(pad "OA13" smd rect
			(at -2.750058 -23.459948 180)
			(size 0.381 1.4478)
			(layers "F.Cu" "F.Mask" "F.Paste")
			(net "GND")
		)
		(pad "OA14" smd rect
			(at -2.750058 -22.86 180)
			(size 0.381 1.4478)
			(layers "F.Cu" "F.Mask" "F.Paste")
			(net "CLK_50M_NCSI_OCP_V3_2_ISO")
		)
		(pad "OB1" smd rect
			(at -5.700014 -30.660086 180)
			(size 0.381 1.4478)
			(layers "F.Cu" "F.Mask" "F.Paste")
			(net "FM_OCP_V3_2_PWR_GOOD")
		)
		(pad "OB2" smd rect
			(at -5.700014 -30.059884 180)
			(size 0.381 1.4478)
			(layers "F.Cu" "F.Mask" "F.Paste")
			(net "OCP_V3_2_MAIN_PWR_EN_R")
		)
		(pad "OB3" smd rect
			(at -5.700014 -29.459936 180)
			(size 0.381 1.4478)
			(layers "F.Cu" "F.Mask" "F.Paste")
			(net "SGPIO_OCP_V3_2_LD_N")
		)
		(pad "OB4" smd rect
			(at -5.700014 -28.859988 180)
			(size 0.381 1.4478)
			(layers "F.Cu" "F.Mask" "F.Paste")
			(net "SGPIO_OCP_V3_2_DATAIN")
		)
		(pad "OB5" smd rect
			(at -5.700014 -28.26004 180)
			(size 0.381 1.4478)
			(layers "F.Cu" "F.Mask" "F.Paste")
			(net "SGPIO_OCP_V3_2_DATAOUT")
		)
		(pad "OB6" smd rect
			(at -5.700014 -27.660092 180)
			(size 0.381 1.4478)
			(layers "F.Cu" "F.Mask" "F.Paste")
			(net "SGPIO_OCP_V3_2_CLK")
		)
		(pad "OB7" smd rect
			(at -5.700014 -27.05989 180)
			(size 0.381 1.4478)
			(layers "F.Cu" "F.Mask" "F.Paste")
			(net "OCP_V3_2_ID0")
		)
		(pad "OB8" smd rect
			(at -5.700014 -26.459942 180)
			(size 0.381 1.4478)
			(layers "F.Cu" "F.Mask" "F.Paste")
			(net "NCSI_OCP_V3_2_RXD1")
		)
		(pad "OB9" smd rect
			(at -5.700014 -25.859994 180)
			(size 0.381 1.4478)
			(layers "F.Cu" "F.Mask" "F.Paste")
			(net "NCSI_OCP_V3_2_RXD0")
		)
		(pad "OB10" smd rect
			(at -5.700014 -25.260046 180)
			(size 0.381 1.4478)
			(layers "F.Cu" "F.Mask" "F.Paste")
			(net "GND")
		)
		(pad "OB11" smd rect
			(at -5.700014 -24.660098 180)
			(size 0.381 1.4478)
			(layers "F.Cu" "F.Mask" "F.Paste")
			(net "CLK_100M_OCP_V3_2_C_DN")
		)
		(pad "OB12" smd rect
			(at -5.700014 -24.059896 180)
			(size 0.381 1.4478)
			(layers "F.Cu" "F.Mask" "F.Paste")
			(net "CLK_100M_OCP_V3_2_C_DP")
		)
		(pad "OB13" smd rect
			(at -5.700014 -23.459948 180)
			(size 0.381 1.4478)
			(layers "F.Cu" "F.Mask" "F.Paste")
			(net "GND")
		)
		(pad "OB14" smd rect
			(at -5.700014 -22.86 180)
			(size 0.381 1.4478)
			(layers "F.Cu" "F.Mask" "F.Paste")
			(net "NCSI_OCP_V3_2_CRS_DV")
		)
	)
)
